(kicad_pcb
	(version 20260206)
	(generator "pcbnew")
	(generator_version "10.0")
	(general
		(thickness 1.6)
		(legacy_teardrops no)
	)
	(paper "A4")
	(title_block
		(title "Bryce Canyon_SCC_16316-1_OCP.brd")
		(comment 1 "Bryce Canyon / footprint 482 of 1561 (U2), pads 1-121 of 896")
	)
	(layers
		(0 "F.Cu" signal "TOP")
		(4 "In1.Cu" signal "L2GND")
		(6 "In2.Cu" signal "L3")
		(8 "In3.Cu" signal "L4VCC")
		(10 "In4.Cu" signal "L5VCC")
		(12 "In5.Cu" signal "L6")
		(14 "In6.Cu" signal "L7GND")
		(2 "B.Cu" signal "BOTTOM")
		(9 "F.Adhes" user "F.Adhesive")
		(11 "B.Adhes" user "B.Adhesive")
		(13 "F.Paste" user "Package Geometry/Pastemask Top")
		(15 "B.Paste" user "Package Geometry/Pastemask Bottom")
		(5 "F.SilkS" user "Ref Des/Silkscreen Top")
		(7 "B.SilkS" user "Ref Des/Silkscreen Bottom")
		(1 "F.Mask" user "Board Geometry/Soldermask Top")
		(3 "B.Mask" user "Board Geometry/Soldermask Bottom")
		(17 "Dwgs.User" user "User.Drawings")
		(19 "Cmts.User" user "User.Comments")
		(21 "Eco1.User" user "User.Eco1")
		(23 "Eco2.User" user "User.Eco2")
		(25 "Edge.Cuts" user "Board Geometry/Outline")
		(27 "Margin" user)
		(31 "F.CrtYd" user "Package Geometry/Place Bound Top")
		(29 "B.CrtYd" user "Package Geometry/Place Bound Bottom")
		(35 "F.Fab" user "Ref Des/Assembly Top")
		(33 "B.Fab" user "Ref Des/Assembly Bottom")
	)
	(footprint ""
		(layer "F.Cu")
		(at 174.999904 -39.99992)
		(property "Reference" "U2"
			(at 0 0 0)
			(layer "F.SilkS")
			(hide yes)
			(effects
				(font
					(size 1.27 1.27)
				)
			)
		)
		(property "Value" "SAS3008C0-1-DB-500020657-1-GP"
			(at -20.374102 -5.0292 0)
			(unlocked yes)
			(layer "F.Fab")
			(hide yes)
			(effects
				(font
					(size 1.016 1.016)
					(thickness 0.1524)
				)
			)
		)
		(property "Device Type" "BGA896D25H78"
			(at -20.374102 -6.5532 0)
			(unlocked yes)
			(layer "F.Fab")
			(hide yes)
			(effects
				(font
					(size 1.016 1.016)
					(thickness 0.1524)
				)
			)
		)
		(duplicate_pad_numbers_are_jumpers no)
		(pad "A2" smd circle
			(at -10.80008 -11.599926)
			(size 0.4064 0.4064)
			(layers "F.Cu" "F.Mask" "F.Paste")
			(net "Net_1158")
		)
		(pad "A3" smd circle
			(at -9.99998 -11.599926)
			(size 0.4064 0.4064)
			(layers "F.Cu" "F.Mask" "F.Paste")
			(net "Net_1159")
		)
		(pad "A4" smd circle
			(at -9.19988 -11.599926)
			(size 0.3556 0.3556)
			(layers "F.Cu" "F.Mask" "F.Paste")
			(net "GND")
		)
		(pad "A5" smd circle
			(at -8.400034 -11.599926)
			(size 0.3556 0.3556)
			(layers "F.Cu" "F.Mask" "F.Paste")
			(net "Net_1160")
		)
		(pad "A6" smd circle
			(at -7.599934 -11.599926)
			(size 0.3556 0.3556)
			(layers "F.Cu" "F.Mask" "F.Paste")
			(net "ICE1_TMS")
		)
		(pad "A7" smd circle
			(at -6.800088 -11.599926)
			(size 0.3556 0.3556)
			(layers "F.Cu" "F.Mask" "F.Paste")
			(net "Net_1161")
		)
		(pad "A8" smd circle
			(at -5.999988 -11.599926)
			(size 0.3556 0.3556)
			(layers "F.Cu" "F.Mask" "F.Paste")
			(net "ICE0_TRST#")
		)
		(pad "A9" smd circle
			(at -5.199888 -11.599926)
			(size 0.3556 0.3556)
			(layers "F.Cu" "F.Mask" "F.Paste")
			(net "ICE0_TCK")
		)
		(pad "A10" smd circle
			(at -4.400042 -11.599926)
			(size 0.3556 0.3556)
			(layers "F.Cu" "F.Mask" "F.Paste")
			(net "ICE1_TDO")
		)
		(pad "A11" smd circle
			(at -3.599942 -11.599926)
			(size 0.3556 0.3556)
			(layers "F.Cu" "F.Mask" "F.Paste")
			(net "GND")
		)
		(pad "A12" smd circle
			(at -2.800096 -11.599926)
			(size 0.3556 0.3556)
			(layers "F.Cu" "F.Mask" "F.Paste")
			(net "PG_CORE")
		)
		(pad "A13" smd circle
			(at -1.999996 -11.599926)
			(size 0.3556 0.3556)
			(layers "F.Cu" "F.Mask" "F.Paste")
			(net "SCC_FULL_PGOOD_LS")
		)
		(pad "A14" smd circle
			(at -1.199896 -11.599926)
			(size 0.3556 0.3556)
			(layers "F.Cu" "F.Mask" "F.Paste")
			(net "HM40ADC_VDDA")
		)
		(pad "A15" smd circle
			(at -0.40005 -11.599926)
			(size 0.3556 0.3556)
			(layers "F.Cu" "F.Mask" "F.Paste")
			(net "GND")
		)
		(pad "A16" smd circle
			(at 0.40005 -11.599926)
			(size 0.3556 0.3556)
			(layers "F.Cu" "F.Mask" "F.Paste")
			(net "IOC_TRST_N")
		)
		(pad "A17" smd circle
			(at 1.199896 -11.599926)
			(size 0.3556 0.3556)
			(layers "F.Cu" "F.Mask" "F.Paste")
			(net "JTAG_IOC_TDI")
		)
		(pad "A18" smd circle
			(at 1.999996 -11.599926)
			(size 0.3556 0.3556)
			(layers "F.Cu" "F.Mask" "F.Paste")
			(net "LSI_IDDT")
		)
		(pad "A19" smd circle
			(at 2.800096 -11.599926)
			(size 0.3556 0.3556)
			(layers "F.Cu" "F.Mask" "F.Paste")
			(net "Net_1152")
		)
		(pad "A20" smd circle
			(at 3.599942 -11.599926)
			(size 0.3556 0.3556)
			(layers "F.Cu" "F.Mask" "F.Paste")
			(net "Net_1153")
		)
		(pad "A21" smd circle
			(at 4.400042 -11.599926)
			(size 0.3556 0.3556)
			(layers "F.Cu" "F.Mask" "F.Paste")
			(net "XM_NOR_CS_N")
		)
		(pad "A22" smd circle
			(at 5.199888 -11.599926)
			(size 0.3556 0.3556)
			(layers "F.Cu" "F.Mask" "F.Paste")
			(net "XM_RB")
		)
		(pad "A23" smd circle
			(at 5.999988 -11.599926)
			(size 0.3556 0.3556)
			(layers "F.Cu" "F.Mask" "F.Paste")
			(net "Net_1148")
		)
		(pad "A24" smd circle
			(at 6.800088 -11.599926)
			(size 0.3556 0.3556)
			(layers "F.Cu" "F.Mask" "F.Paste")
			(net "XM_WE_N")
		)
		(pad "A25" smd circle
			(at 7.599934 -11.599926)
			(size 0.3556 0.3556)
			(layers "F.Cu" "F.Mask" "F.Paste")
			(net "XM_WP")
		)
		(pad "A26" smd circle
			(at 8.400034 -11.599926)
			(size 0.3556 0.3556)
			(layers "F.Cu" "F.Mask" "F.Paste")
			(net "XM_ADDR_3")
		)
		(pad "A27" smd circle
			(at 9.19988 -11.599926)
			(size 0.3556 0.3556)
			(layers "F.Cu" "F.Mask" "F.Paste")
			(net "Net_1149")
		)
		(pad "A28" smd circle
			(at 9.99998 -11.599926)
			(size 0.4064 0.4064)
			(layers "F.Cu" "F.Mask" "F.Paste")
			(net "XM_ADDR_4")
		)
		(pad "A29" smd circle
			(at 10.80008 -11.599926)
			(size 0.4064 0.4064)
			(layers "F.Cu" "F.Mask" "F.Paste")
			(net "XM_DATA_11")
		)
		(pad "AA1" smd circle
			(at -11.599926 4.400042)
			(size 0.3556 0.3556)
			(layers "F.Cu" "F.Mask" "F.Paste")
			(net "PHY_IOC_TO_SCC_45_DP")
		)
		(pad "AA2" smd circle
			(at -10.80008 4.400042)
			(size 0.3556 0.3556)
			(layers "F.Cu" "F.Mask" "F.Paste")
			(net "PHY_IOC_TO_SCC_45_DN")
		)
		(pad "AA3" smd circle
			(at -9.99998 4.400042)
			(size 0.3556 0.3556)
			(layers "F.Cu" "F.Mask" "F.Paste")
			(net "GND")
		)
		(pad "AA4" smd circle
			(at -9.19988 4.400042)
			(size 0.3556 0.3556)
			(layers "F.Cu" "F.Mask" "F.Paste")
			(net "PHY_SCC_TO_IOC_C_45_DP")
		)
		(pad "AA5" smd circle
			(at -8.400034 4.400042)
			(size 0.3556 0.3556)
			(layers "F.Cu" "F.Mask" "F.Paste")
			(net "PHY_SCC_TO_IOC_C_45_DN")
		)
		(pad "AA6" smd circle
			(at -7.599934 4.400042)
			(size 0.3556 0.3556)
			(layers "F.Cu" "F.Mask" "F.Paste")
			(net "GND")
		)
		(pad "AA7" smd circle
			(at -6.800088 4.400042)
			(size 0.3556 0.3556)
			(layers "F.Cu" "F.Mask" "F.Paste")
			(net "GND")
		)
		(pad "AA8" smd circle
			(at -5.999988 4.400042)
			(size 0.3556 0.3556)
			(layers "F.Cu" "F.Mask" "F.Paste")
			(net "GND")
		)
		(pad "AA9" smd circle
			(at -5.199888 4.400042)
			(size 0.3556 0.3556)
			(layers "F.Cu" "F.Mask" "F.Paste")
			(net "GND")
		)
		(pad "AA10" smd circle
			(at -4.400042 4.400042)
			(size 0.3556 0.3556)
			(layers "F.Cu" "F.Mask" "F.Paste")
			(net "GND")
		)
		(pad "AA11" smd circle
			(at -3.599942 4.400042)
			(size 0.3556 0.3556)
			(layers "F.Cu" "F.Mask" "F.Paste")
			(net "GND")
		)
		(pad "AA12" smd circle
			(at -2.800096 4.400042)
			(size 0.3556 0.3556)
			(layers "F.Cu" "F.Mask" "F.Paste")
			(net "GND")
		)
		(pad "AA13" smd circle
			(at -1.999996 4.400042)
			(size 0.3556 0.3556)
			(layers "F.Cu" "F.Mask" "F.Paste")
			(net "GND")
		)
		(pad "AA14" smd circle
			(at -1.199896 4.400042)
			(size 0.3556 0.3556)
			(layers "F.Cu" "F.Mask" "F.Paste")
			(net "GND")
		)
		(pad "AA15" smd circle
			(at -0.40005 4.400042)
			(size 0.3556 0.3556)
			(layers "F.Cu" "F.Mask" "F.Paste")
			(net "GND")
		)
		(pad "AA16" smd circle
			(at 0.40005 4.400042)
			(size 0.3556 0.3556)
			(layers "F.Cu" "F.Mask" "F.Paste")
			(net "GND")
		)
		(pad "AA17" smd circle
			(at 1.199896 4.400042)
			(size 0.3556 0.3556)
			(layers "F.Cu" "F.Mask" "F.Paste")
			(net "GND")
		)
		(pad "AA18" smd circle
			(at 1.999996 4.400042)
			(size 0.3556 0.3556)
			(layers "F.Cu" "F.Mask" "F.Paste")
			(net "GND")
		)
		(pad "AA19" smd circle
			(at 2.800096 4.400042)
			(size 0.3556 0.3556)
			(layers "F.Cu" "F.Mask" "F.Paste")
			(net "GND")
		)
		(pad "AA20" smd circle
			(at 3.599942 4.400042)
			(size 0.3556 0.3556)
			(layers "F.Cu" "F.Mask" "F.Paste")
			(net "GND")
		)
		(pad "AA21" smd circle
			(at 4.400042 4.400042)
			(size 0.3556 0.3556)
			(layers "F.Cu" "F.Mask" "F.Paste")
			(net "GND")
		)
		(pad "AA22" smd circle
			(at 5.199888 4.400042)
			(size 0.3556 0.3556)
			(layers "F.Cu" "F.Mask" "F.Paste")
			(net "GND")
		)
		(pad "AA23" smd circle
			(at 5.999988 4.400042)
			(size 0.3556 0.3556)
			(layers "F.Cu" "F.Mask" "F.Paste")
			(net "PLL_VDD")
		)
		(pad "AA24" smd circle
			(at 6.800088 4.400042)
			(size 0.3556 0.3556)
			(layers "F.Cu" "F.Mask" "F.Paste")
			(net "GND")
		)
		(pad "AA25" smd circle
			(at 7.599934 4.400042)
			(size 0.3556 0.3556)
			(layers "F.Cu" "F.Mask" "F.Paste")
			(net "GND")
		)
		(pad "AA26" smd circle
			(at 8.400034 4.400042)
			(size 0.3556 0.3556)
			(layers "F.Cu" "F.Mask" "F.Paste")
			(net "GND")
		)
		(pad "AA27" smd circle
			(at 9.19988 4.400042)
			(size 0.3556 0.3556)
			(layers "F.Cu" "F.Mask" "F.Paste")
			(net "P1V8_C")
		)
		(pad "AA28" smd circle
			(at 9.99998 4.400042)
			(size 0.3556 0.3556)
			(layers "F.Cu" "F.Mask" "F.Paste")
			(net "IOC_GPIO_36")
		)
		(pad "AA29" smd circle
			(at 10.80008 4.400042)
			(size 0.3556 0.3556)
			(layers "F.Cu" "F.Mask" "F.Paste")
			(net "IOC_GPIO_33")
		)
		(pad "AA30" smd circle
			(at 11.599926 4.400042)
			(size 0.3556 0.3556)
			(layers "F.Cu" "F.Mask" "F.Paste")
			(net "IOC_GPIO_37")
		)
		(pad "AB1" smd circle
			(at -11.599926 5.199888)
			(size 0.3556 0.3556)
			(layers "F.Cu" "F.Mask" "F.Paste")
			(net "PHY_IOC_TO_SCC_44_DP")
		)
		(pad "AB2" smd circle
			(at -10.80008 5.199888)
			(size 0.3556 0.3556)
			(layers "F.Cu" "F.Mask" "F.Paste")
			(net "PHY_IOC_TO_SCC_44_DN")
		)
		(pad "AB3" smd circle
			(at -9.99998 5.199888)
			(size 0.3556 0.3556)
			(layers "F.Cu" "F.Mask" "F.Paste")
			(net "GND")
		)
		(pad "AB4" smd circle
			(at -9.19988 5.199888)
			(size 0.3556 0.3556)
			(layers "F.Cu" "F.Mask" "F.Paste")
			(net "PHY_SCC_TO_IOC_C_44_DP")
		)
		(pad "AB5" smd circle
			(at -8.400034 5.199888)
			(size 0.3556 0.3556)
			(layers "F.Cu" "F.Mask" "F.Paste")
			(net "PHY_SCC_TO_IOC_C_44_DN")
		)
		(pad "AB6" smd circle
			(at -7.599934 5.199888)
			(size 0.3556 0.3556)
			(layers "F.Cu" "F.Mask" "F.Paste")
			(net "GND")
		)
		(pad "AB7" smd circle
			(at -6.800088 5.199888)
			(size 0.3556 0.3556)
			(layers "F.Cu" "F.Mask" "F.Paste")
			(net "SAS0_AVDD")
		)
		(pad "AB8" smd circle
			(at -5.999988 5.199888)
			(size 0.3556 0.3556)
			(layers "F.Cu" "F.Mask" "F.Paste")
			(net "GND")
		)
		(pad "AB9" smd circle
			(at -5.199888 5.199888)
			(size 0.3556 0.3556)
			(layers "F.Cu" "F.Mask" "F.Paste")
			(net "GND")
		)
		(pad "AB10" smd circle
			(at -4.400042 5.199888)
			(size 0.3556 0.3556)
			(layers "F.Cu" "F.Mask" "F.Paste")
			(net "GND")
		)
		(pad "AB11" smd circle
			(at -3.599942 5.199888)
			(size 0.3556 0.3556)
			(layers "F.Cu" "F.Mask" "F.Paste")
			(net "GND")
		)
		(pad "AB12" smd circle
			(at -2.800096 5.199888)
			(size 0.3556 0.3556)
			(layers "F.Cu" "F.Mask" "F.Paste")
			(net "GND")
		)
		(pad "AB13" smd circle
			(at -1.999996 5.199888)
			(size 0.3556 0.3556)
			(layers "F.Cu" "F.Mask" "F.Paste")
			(net "GND")
		)
		(pad "AB14" smd circle
			(at -1.199896 5.199888)
			(size 0.3556 0.3556)
			(layers "F.Cu" "F.Mask" "F.Paste")
			(net "GND")
		)
		(pad "AB15" smd circle
			(at -0.40005 5.199888)
			(size 0.3556 0.3556)
			(layers "F.Cu" "F.Mask" "F.Paste")
			(net "GND")
		)
		(pad "AB16" smd circle
			(at 0.40005 5.199888)
			(size 0.3556 0.3556)
			(layers "F.Cu" "F.Mask" "F.Paste")
			(net "GND")
		)
		(pad "AB17" smd circle
			(at 1.199896 5.199888)
			(size 0.3556 0.3556)
			(layers "F.Cu" "F.Mask" "F.Paste")
			(net "GND")
		)
		(pad "AB18" smd circle
			(at 1.999996 5.199888)
			(size 0.3556 0.3556)
			(layers "F.Cu" "F.Mask" "F.Paste")
			(net "GND")
		)
		(pad "AB19" smd circle
			(at 2.800096 5.199888)
			(size 0.3556 0.3556)
			(layers "F.Cu" "F.Mask" "F.Paste")
			(net "GND")
		)
		(pad "AB20" smd circle
			(at 3.599942 5.199888)
			(size 0.3556 0.3556)
			(layers "F.Cu" "F.Mask" "F.Paste")
			(net "GND")
		)
		(pad "AB21" smd circle
			(at 4.400042 5.199888)
			(size 0.3556 0.3556)
			(layers "F.Cu" "F.Mask" "F.Paste")
			(net "GND")
		)
		(pad "AB22" smd circle
			(at 5.199888 5.199888)
			(size 0.3556 0.3556)
			(layers "F.Cu" "F.Mask" "F.Paste")
			(net "GND")
		)
		(pad "AB23" smd circle
			(at 5.999988 5.199888)
			(size 0.3556 0.3556)
			(layers "F.Cu" "F.Mask" "F.Paste")
			(net "GND")
		)
		(pad "AB24" smd circle
			(at 6.800088 5.199888)
			(size 0.3556 0.3556)
			(layers "F.Cu" "F.Mask" "F.Paste")
			(net "GND")
		)
		(pad "AB25" smd circle
			(at 7.599934 5.199888)
			(size 0.3556 0.3556)
			(layers "F.Cu" "F.Mask" "F.Paste")
			(net "GND")
		)
		(pad "AB26" smd circle
			(at 8.400034 5.199888)
			(size 0.3556 0.3556)
			(layers "F.Cu" "F.Mask" "F.Paste")
			(net "P1V8_C")
		)
		(pad "AB27" smd circle
			(at 9.19988 5.199888)
			(size 0.3556 0.3556)
			(layers "F.Cu" "F.Mask" "F.Paste")
			(net "GND")
		)
		(pad "AB28" smd circle
			(at 9.99998 5.199888)
			(size 0.3556 0.3556)
			(layers "F.Cu" "F.Mask" "F.Paste")
			(net "IOC_GPIO_34")
		)
		(pad "AB29" smd circle
			(at 10.80008 5.199888)
			(size 0.3556 0.3556)
			(layers "F.Cu" "F.Mask" "F.Paste")
			(net "IOC_GPIO_23")
		)
		(pad "AB30" smd circle
			(at 11.599926 5.199888)
			(size 0.3556 0.3556)
			(layers "F.Cu" "F.Mask" "F.Paste")
			(net "IOC_GPIO_35")
		)
		(pad "AC1" smd circle
			(at -11.599926 5.999988)
			(size 0.3556 0.3556)
			(layers "F.Cu" "F.Mask" "F.Paste")
			(net "SAS0_VDDH")
		)
		(pad "AC2" smd circle
			(at -10.80008 5.999988)
			(size 0.3556 0.3556)
			(layers "F.Cu" "F.Mask" "F.Paste")
			(net "GND")
		)
		(pad "AC3" smd circle
			(at -9.99998 5.999988)
			(size 0.3556 0.3556)
			(layers "F.Cu" "F.Mask" "F.Paste")
			(net "GND")
		)
		(pad "AC4" smd circle
			(at -9.19988 5.999988)
			(size 0.3556 0.3556)
			(layers "F.Cu" "F.Mask" "F.Paste")
			(net "SAS0_AVDD")
		)
		(pad "AC5" smd circle
			(at -8.400034 5.999988)
			(size 0.3556 0.3556)
			(layers "F.Cu" "F.Mask" "F.Paste")
			(net "GND")
		)
		(pad "AC6" smd circle
			(at -7.599934 5.999988)
			(size 0.3556 0.3556)
			(layers "F.Cu" "F.Mask" "F.Paste")
			(net "SAS0_VDDH")
		)
		(pad "AC7" smd circle
			(at -6.800088 5.999988)
			(size 0.3556 0.3556)
			(layers "F.Cu" "F.Mask" "F.Paste")
			(net "GND")
		)
		(pad "AC8" smd circle
			(at -5.999988 5.999988)
			(size 0.3556 0.3556)
			(layers "F.Cu" "F.Mask" "F.Paste")
			(net "GND")
		)
		(pad "AC9" smd circle
			(at -5.199888 5.999988)
			(size 0.3556 0.3556)
			(layers "F.Cu" "F.Mask" "F.Paste")
			(net "GND")
		)
		(pad "AC10" smd circle
			(at -4.400042 5.999988)
			(size 0.3556 0.3556)
			(layers "F.Cu" "F.Mask" "F.Paste")
			(net "GND")
		)
		(pad "AC11" smd circle
			(at -3.599942 5.999988)
			(size 0.3556 0.3556)
			(layers "F.Cu" "F.Mask" "F.Paste")
			(net "PCE_AVDD")
		)
		(pad "AC12" smd circle
			(at -2.800096 5.999988)
			(size 0.3556 0.3556)
			(layers "F.Cu" "F.Mask" "F.Paste")
			(net "GND")
		)
		(pad "AC13" smd circle
			(at -1.999996 5.999988)
			(size 0.3556 0.3556)
			(layers "F.Cu" "F.Mask" "F.Paste")
			(net "GND")
		)
		(pad "AC14" smd circle
			(at -1.199896 5.999988)
			(size 0.3556 0.3556)
			(layers "F.Cu" "F.Mask" "F.Paste")
			(net "GND")
		)
		(pad "AC15" smd circle
			(at -0.40005 5.999988)
			(size 0.3556 0.3556)
			(layers "F.Cu" "F.Mask" "F.Paste")
			(net "GND")
		)
		(pad "AC16" smd circle
			(at 0.40005 5.999988)
			(size 0.3556 0.3556)
			(layers "F.Cu" "F.Mask" "F.Paste")
			(net "GND")
		)
		(pad "AC17" smd circle
			(at 1.199896 5.999988)
			(size 0.3556 0.3556)
			(layers "F.Cu" "F.Mask" "F.Paste")
			(net "GND")
		)
		(pad "AC18" smd circle
			(at 1.999996 5.999988)
			(size 0.3556 0.3556)
			(layers "F.Cu" "F.Mask" "F.Paste")
			(net "GND")
		)
		(pad "AC19" smd circle
			(at 2.800096 5.999988)
			(size 0.3556 0.3556)
			(layers "F.Cu" "F.Mask" "F.Paste")
			(net "GND")
		)
		(pad "AC20" smd circle
			(at 3.599942 5.999988)
			(size 0.3556 0.3556)
			(layers "F.Cu" "F.Mask" "F.Paste")
			(net "GND")
		)
		(pad "AC21" smd circle
			(at 4.400042 5.999988)
			(size 0.3556 0.3556)
			(layers "F.Cu" "F.Mask" "F.Paste")
			(net "GND")
		)
		(pad "AC22" smd circle
			(at 5.199888 5.999988)
			(size 0.3556 0.3556)
			(layers "F.Cu" "F.Mask" "F.Paste")
			(net "GND")
		)
		(pad "AC23" smd circle
			(at 5.999988 5.999988)
			(size 0.3556 0.3556)
			(layers "F.Cu" "F.Mask" "F.Paste")
			(net "GND")
		)
		(pad "AC24" smd circle
			(at 6.800088 5.999988)
			(size 0.3556 0.3556)
			(layers "F.Cu" "F.Mask" "F.Paste")
			(net "GND")
		)
		(pad "AC25" smd circle
			(at 7.599934 5.999988)
			(size 0.3556 0.3556)
			(layers "F.Cu" "F.Mask" "F.Paste")
			(net "GND")
		)
		(pad "AC26" smd circle
			(at 8.400034 5.999988)
			(size 0.3556 0.3556)
			(layers "F.Cu" "F.Mask" "F.Paste")
			(net "GND")
		)
		(pad "AC27" smd circle
			(at 9.19988 5.999988)
			(size 0.3556 0.3556)
			(layers "F.Cu" "F.Mask" "F.Paste")
			(net "P1V8_C")
		)
		(pad "AC28" smd circle
			(at 9.99998 5.999988)
			(size 0.3556 0.3556)
			(layers "F.Cu" "F.Mask" "F.Paste")
			(net "IOC_GPIO_28")
		)
		(pad "AC29" smd circle
			(at 10.80008 5.999988)
			(size 0.3556 0.3556)
			(layers "F.Cu" "F.Mask" "F.Paste")
			(net "IOC_GPIO_30")
		)
		(pad "AC30" smd circle
			(at 11.599926 5.999988)
			(size 0.3556 0.3556)
			(layers "F.Cu" "F.Mask" "F.Paste")
			(net "IOC_GPIO_8")
		)
		(pad "AD1" smd circle
			(at -11.599926 6.800088)
			(size 0.3556 0.3556)
			(layers "F.Cu" "F.Mask" "F.Paste")
			(net "PHY_IOC_TO_SCC_43_DP")
		)
		(pad "AD2" smd circle
			(at -10.80008 6.800088)
			(size 0.3556 0.3556)
			(layers "F.Cu" "F.Mask" "F.Paste")
			(net "PHY_IOC_TO_SCC_43_DN")
		)
		(pad "AD3" smd circle
			(at -9.99998 6.800088)
			(size 0.3556 0.3556)
			(layers "F.Cu" "F.Mask" "F.Paste")
			(net "GND")
		)
	)
)
